FILE_TYPE = CONNECTIVITY;
{Allegro Design Entry HDL 17.2-2016 S081 (4005846) 1/11/2022}
"PAGE_NUMBER" = 76;
0"NC";
1"PVCCFA_EHV_CPU0\g";
2"PVCCFA_EHV_FIVRA_CPU0\g";
3"PVCCINFAON_CPU0\g";
4"PVNN_MAIN_CPU0\g";
5"PVCCD_HV_CPU0\g";
6"PVCCIN_CPU0\g";
7"GND\g";
8"GND\g";
9"GND\g";
10"GND\g";
11"GND\g";
12"GND\g";
%"Q_CAP"
"1","(-3925,4025)","0","pure_quanta","I1";
;
PART_NUMBER"CH647KMEA04"
TOLERANCE"20%"
VOLTAGE"4V"
PACK_TYPE"C0805"
VALUE"47UF"
MATERIAL"X6S"
$LOCATION"C494"
CDS_LIB"pure_quanta"
CDS_LOCATION"C494"
$SEC"1"
CDS_SEC"1";
"B"
$PN"2"10;
"A"
$PN"1"2;
%"Q_CAP"
"1","(-3475,6100)","0","pure_quanta","I10";
;
PART_NUMBER"CH647KMEA04"
VALUE"47UF"
TOLERANCE"20%"
VOLTAGE"4V"
PACK_TYPE"C0805"
MATERIAL"X6S"
$LOCATION"C504"
CDS_LIB"pure_quanta"
CDS_LOCATION"C504"
$SEC"1"
CDS_SEC"1";
"B"
$PN"2"9;
"A"
$PN"1"1;
%"Q_CAP"
"1","(-3025,6100)","0","pure_quanta","I11";
;
PART_NUMBER"CH647KMEA04"
TOLERANCE"20%"
VOLTAGE"4V"
PACK_TYPE"C0805"
MATERIAL"X6S"
VALUE"47UF"
$LOCATION"C508"
CDS_LIB"pure_quanta"
CDS_LOCATION"C508"
$SEC"1"
CDS_SEC"1";
"B"
$PN"2"9;
"A"
$PN"1"1;
%"UNIVERSAL_POWER"
"1","(-3925,6375)","0","logical_power","I12";
;
HDL_POWER"PVCCFA_EHV_CPU0"
CDS_LIB"logical_power";
"A"1;
%"Q_CAP"
"1","(-3925,7100)","0","pure_quanta","I13";
;
PART_NUMBER"CH647KMEA04"
TOLERANCE"20%"
VOLTAGE"4V"
PACK_TYPE"C0805"
VALUE"47UF"
MATERIAL"X6S"
$LOCATION"C1399"
CDS_LIB"pure_quanta"
CDS_LOCATION"C1399"
$SEC"1"
CDS_SEC"1";
"B"
$PN"2"7;
"A"
$PN"1"4;
%"Q_CAP"
"1","(-3475,7100)","0","pure_quanta","I14";
;
PART_NUMBER"CH647KMEA04"
TOLERANCE"20%"
VOLTAGE"4V"
PACK_TYPE"C0805"
VALUE"47UF"
MATERIAL"X6S"
$LOCATION"C1400"
CDS_LIB"pure_quanta"
CDS_LOCATION"C1400"
$SEC"1"
CDS_SEC"1";
"B"
$PN"2"7;
"A"
$PN"1"4;
%"UNIVERSAL_GND"
"1","(-3075,6750)","0","logical_power","I15";
;
CDS_LIB"logical_power"
HDL_POWER"GND";
"A"7;
%"Q_CAP"
"1","(-3075,7100)","0","pure_quanta","I16";
;
PART_NUMBER"CH622KMEB01"
TOLERANCE"20%"
MATERIAL"X6S"
VOLTAGE"4V"
PACK_TYPE"C0402"
VALUE"22UF"
$LOCATION"C1362"
CDS_LIB"pure_quanta"
CDS_LOCATION"C1362"
$SEC"1"
CDS_SEC"1";
"B"
$PN"2"7;
"A"
$PN"1"4;
%"UNIVERSAL_POWER"
"1","(-3925,7375)","0","logical_power","I17";
;
HDL_POWER"PVNN_MAIN_CPU0"
CDS_LIB"logical_power";
"A"4;
%"Q_CAP"
"1","(-3925,7950)","0","pure_quanta","I18";
;
PART_NUMBER"CH647KMEA04"
VALUE"47UF"
TOLERANCE"20%"
VOLTAGE"4V"
PACK_TYPE"C0805"
MATERIAL"X6S"
$LOCATION"C499"
CDS_LIB"pure_quanta"
CDS_LOCATION"C499"
$SEC"1"
CDS_SEC"1";
"B"
$PN"2"11;
"A"
$PN"1"5;
%"UNIVERSAL_POWER"
"1","(-3925,8225)","0","logical_power","I19";
;
HDL_POWER"PVCCD_HV_CPU0"
CDS_LIB"logical_power";
"A"5;
%"Q_CAP"
"1","(-3475,4025)","0","pure_quanta","I2";
;
PART_NUMBER"CH647KMEA04"
TOLERANCE"20%"
VOLTAGE"4V"
PACK_TYPE"C0805"
VALUE"47UF"
MATERIAL"X6S"
$LOCATION"C498"
CDS_LIB"pure_quanta"
CDS_LOCATION"C498"
$SEC"1"
CDS_SEC"1";
"B"
$PN"2"10;
"A"
$PN"1"2;
%"Q_CAP"
"1","(-3475,7950)","0","pure_quanta","I20";
;
PART_NUMBER"CH647KMEA04"
VALUE"47UF"
TOLERANCE"20%"
VOLTAGE"4V"
PACK_TYPE"C0805"
MATERIAL"X6S"
$LOCATION"C503"
CDS_LIB"pure_quanta"
CDS_LOCATION"C503"
$SEC"1"
CDS_SEC"1";
"B"
$PN"2"11;
"A"
$PN"1"5;
%"Q_CAP"
"1","(-3025,7950)","0","pure_quanta","I21";
;
PART_NUMBER"CH647KMEA04"
VALUE"47UF"
TOLERANCE"20%"
VOLTAGE"4V"
PACK_TYPE"C0805"
MATERIAL"X6S"
$LOCATION"C507"
CDS_LIB"pure_quanta"
CDS_LOCATION"C507"
$SEC"1"
CDS_SEC"1";
"B"
$PN"2"11;
"A"
$PN"1"5;
%"Q_CAP"
"1","(-3925,8825)","0","pure_quanta","I22";
;
PART_NUMBER"CH647KMEA04"
TOLERANCE"20%"
VOLTAGE"4V"
PACK_TYPE"C0805"
VALUE"47UF"
MATERIAL"X6S"
$LOCATION"C386"
CDS_LIB"pure_quanta"
$LOCATION"C386"
CDS_LOCATION"C386"
$SEC"1"
CDS_SEC"1";
"B"
$PN"2"12;
"A"
$PN"1"6;
%"Q_CAP"
"1","(-3475,8825)","0","pure_quanta","I23";
;
PART_NUMBER"CH647KMEA04"
TOLERANCE"20%"
VOLTAGE"4V"
PACK_TYPE"C0805"
VALUE"47UF"
MATERIAL"X6S"
$LOCATION"C388"
CDS_LIB"pure_quanta"
$LOCATION"C388"
CDS_LOCATION"C388"
$SEC"1"
CDS_SEC"1";
"B"
$PN"2"12;
"A"
$PN"1"6;
%"UNIVERSAL_POWER"
"1","(-3925,9100)","0","logical_power","I24";
;
HDL_POWER"PVCCIN_CPU0"
CDS_LIB"logical_power";
"A"6;
%"Q_CAP"
"1","(-3025,8825)","0","pure_quanta","I25";
;
PART_NUMBER"CH647KMEA04"
TOLERANCE"20%"
VOLTAGE"4V"
PACK_TYPE"C0805"
VALUE"47UF"
MATERIAL"X6S"
$LOCATION"C390"
CDS_LIB"pure_quanta"
$LOCATION"C390"
CDS_LOCATION"C390"
$SEC"1"
CDS_SEC"1";
"B"
$PN"2"12;
"A"
$PN"1"6;
%"Q_CAP"
"1","(-2575,4025)","0","pure_quanta","I26";
;
PART_NUMBER"CH647KMEA04"
TOLERANCE"20%"
VOLTAGE"4V"
PACK_TYPE"C0805"
VALUE"47UF"
MATERIAL"X6S"
$LOCATION"C506"
CDS_LIB"pure_quanta"
CDS_LOCATION"C506"
$SEC"1"
CDS_SEC"1";
"B"
$PN"2"10;
"A"
$PN"1"2;
%"Q_CAP"
"1","(-2125,4025)","0","pure_quanta","I27";
;
PART_NUMBER"CH647KMEA04"
TOLERANCE"20%"
VOLTAGE"4V"
PACK_TYPE"C0805"
VALUE"47UF"
MATERIAL"X6S"
$LOCATION"C510"
CDS_LIB"pure_quanta"
CDS_LOCATION"C510"
$SEC"1"
CDS_SEC"1";
"B"
$PN"2"10;
"A"
$PN"1"2;
%"Q_CAP"
"1","(-1675,4025)","0","pure_quanta","I28";
;
PART_NUMBER"CH647KMEA04"
TOLERANCE"20%"
VOLTAGE"4V"
PACK_TYPE"C0805"
VALUE"47UF"
MATERIAL"X6S"
$LOCATION"C514"
CDS_LIB"pure_quanta"
CDS_LOCATION"C514"
$SEC"1"
CDS_SEC"1";
"B"
$PN"2"10;
"A"
$PN"1"2;
%"Q_CAP"
"1","(-1225,4025)","0","pure_quanta","I29";
;
PART_NUMBER"CH647KMEA04"
TOLERANCE"20%"
VOLTAGE"4V"
PACK_TYPE"C0805"
VALUE"47UF"
MATERIAL"X6S"
$LOCATION"C517"
CDS_LIB"pure_quanta"
CDS_LOCATION"C517"
$SEC"1"
CDS_SEC"1";
"B"
$PN"2"10;
"A"
$PN"1"2;
%"Q_CAP"
"1","(-3025,4025)","0","pure_quanta","I3";
;
PART_NUMBER"CH647KMEA04"
TOLERANCE"20%"
VOLTAGE"4V"
PACK_TYPE"C0805"
VALUE"47UF"
MATERIAL"X6S"
$LOCATION"C502"
CDS_LIB"pure_quanta"
CDS_LOCATION"C502"
$SEC"1"
CDS_SEC"1";
"B"
$PN"2"10;
"A"
$PN"1"2;
%"UNIVERSAL_GND"
"1","(-2575,4725)","0","logical_power","I30";
;
CDS_LIB"logical_power"
HDL_POWER"GND";
"A"8;
%"Q_CAP"
"1","(-2575,5075)","0","pure_quanta","I31";
;
PART_NUMBER"CH647KMEA04"
MATERIAL"X6S"
TOLERANCE"20%"
VOLTAGE"4V"
PACK_TYPE"C0805"
VALUE"47UF"
$LOCATION"C531"
CDS_LIB"pure_quanta"
CDS_LOCATION"C531"
$SEC"1"
CDS_SEC"1";
"B"
$PN"2"8;
"A"
$PN"1"3;
%"Q_CAP"
"1","(-2575,6100)","0","pure_quanta","I32";
;
PART_NUMBER"CH647KMEA04"
VALUE"47UF"
TOLERANCE"20%"
VOLTAGE"4V"
PACK_TYPE"C0805"
MATERIAL"X6S"
$LOCATION"C512"
CDS_LIB"pure_quanta"
CDS_LOCATION"C512"
$SEC"1"
CDS_SEC"1";
"B"
$PN"2"9;
"A"
$PN"1"1;
%"Q_CAP"
"1","(-2125,6100)","0","pure_quanta","I33";
;
PART_NUMBER"CH647LME900"
TOLERANCE"20%"
MATERIAL"X6S"
PACK_TYPE"C0603"
VOLTAGE"2.5V"
VALUE"47UF"
$LOCATION"C516"
CDS_LIB"pure_quanta"
CDS_LOCATION"C516"
$SEC"1"
CDS_SEC"1";
"B"
$PN"2"9;
"A"
$PN"1"1;
%"UNIVERSAL_GND"
"1","(-1675,5750)","0","logical_power","I34";
;
CDS_LIB"logical_power"
HDL_POWER"GND";
"A"9;
%"Q_CAP"
"1","(-1675,6100)","0","pure_quanta","I35";
;
PART_NUMBER"CH647LME900"
TOLERANCE"20%"
VOLTAGE"2.5V"
MATERIAL"X6S"
PACK_TYPE"C0603"
VALUE"47UF"
$LOCATION"C519"
CDS_LIB"pure_quanta"
CDS_LOCATION"C519"
$SEC"1"
CDS_SEC"1";
"B"
$PN"2"9;
"A"
$PN"1"1;
%"Q_CAP"
"1","(-775,4025)","0","pure_quanta","I36";
;
PART_NUMBER"CH647KMEA04"
TOLERANCE"20%"
VOLTAGE"4V"
PACK_TYPE"C0805"
VALUE"47UF"
MATERIAL"X6S"
$LOCATION"C520"
CDS_LIB"pure_quanta"
CDS_LOCATION"C520"
$SEC"1"
CDS_SEC"1";
"B"
$PN"2"10;
"A"
$PN"1"2;
%"Q_CAP"
"1","(-325,4025)","0","pure_quanta","I37";
;
PART_NUMBER"CH647KMEA04"
TOLERANCE"20%"
VOLTAGE"4V"
PACK_TYPE"C0805"
VALUE"47UF"
MATERIAL"X6S"
$LOCATION"C521"
CDS_LIB"pure_quanta"
CDS_LOCATION"C521"
$SEC"1"
CDS_SEC"1";
"B"
$PN"2"10;
"A"
$PN"1"2;
%"Q_CAP"
"1","(125,4025)","0","pure_quanta","I38";
;
PART_NUMBER"CH647KMEA04"
TOLERANCE"20%"
VOLTAGE"4V"
PACK_TYPE"C0805"
VALUE"47UF"
MATERIAL"X6S"
$LOCATION"C523"
CDS_LIB"pure_quanta"
CDS_LOCATION"C523"
$SEC"1"
CDS_SEC"1";
"B"
$PN"2"10;
"A"
$PN"1"2;
%"Q_CAP"
"1","(575,4025)","0","pure_quanta","I39";
;
PART_NUMBER"CH647KMEA04"
TOLERANCE"20%"
VOLTAGE"4V"
PACK_TYPE"C0805"
VALUE"47UF"
MATERIAL"X6S"
$LOCATION"C526"
CDS_LIB"pure_quanta"
CDS_LOCATION"C526"
$SEC"1"
CDS_SEC"1";
"B"
$PN"2"10;
"A"
$PN"1"2;
%"UNIVERSAL_POWER"
"1","(-3925,4300)","0","logical_power","I4";
;
HDL_POWER"PVCCFA_EHV_FIVRA_CPU0"
CDS_LIB"logical_power";
"A"2;
%"UNIVERSAL_GND"
"1","(1025,3675)","0","logical_power","I40";
;
CDS_LIB"logical_power"
HDL_POWER"GND";
"A"10;
%"Q_CAP"
"1","(1025,4025)","0","pure_quanta","I41";
;
PART_NUMBER"CH647KMEA04"
TOLERANCE"20%"
VOLTAGE"4V"
PACK_TYPE"C0805"
VALUE"47UF"
MATERIAL"X6S"
$LOCATION"C529"
CDS_LIB"pure_quanta"
CDS_LOCATION"C529"
$SEC"1"
CDS_SEC"1";
"B"
$PN"2"10;
"A"
$PN"1"2;
%"UNIVERSAL_GND"
"1","(-2575,7625)","0","logical_power","I42";
;
CDS_LIB"logical_power"
HDL_POWER"GND";
"A"11;
%"Q_CAP"
"1","(-2575,7950)","0","pure_quanta","I43";
;
PART_NUMBER"CH647KMEA04"
VALUE"47UF"
TOLERANCE"20%"
VOLTAGE"4V"
PACK_TYPE"C0805"
MATERIAL"X6S"
$LOCATION"C511"
CDS_LIB"pure_quanta"
CDS_LOCATION"C511"
$SEC"1"
CDS_SEC"1";
"B"
$PN"2"11;
"A"
$PN"1"5;
%"Q_CAP"
"1","(-2575,8825)","0","pure_quanta","I44";
;
PART_NUMBER"CH647KMEA04"
TOLERANCE"20%"
VOLTAGE"4V"
PACK_TYPE"C0805"
VALUE"47UF"
MATERIAL"X6S"
$LOCATION"C392"
CDS_LIB"pure_quanta"
$LOCATION"C392"
CDS_LOCATION"C392"
$SEC"1"
CDS_SEC"1";
"B"
$PN"2"12;
"A"
$PN"1"6;
%"Q_CAP"
"1","(-2125,8825)","0","pure_quanta","I45";
;
PART_NUMBER"CH647KMEA04"
TOLERANCE"20%"
VOLTAGE"4V"
PACK_TYPE"C0805"
VALUE"47UF"
MATERIAL"X6S"
$LOCATION"C394"
CDS_LIB"pure_quanta"
$LOCATION"C394"
CDS_LOCATION"C394"
$SEC"1"
CDS_SEC"1";
"B"
$PN"2"12;
"A"
$PN"1"6;
%"Q_CAP"
"1","(-1675,8825)","0","pure_quanta","I46";
;
PART_NUMBER"CH647KMEA04"
TOLERANCE"20%"
VOLTAGE"4V"
PACK_TYPE"C0805"
VALUE"47UF"
MATERIAL"X6S"
$LOCATION"C396"
CDS_LIB"pure_quanta"
$LOCATION"C396"
CDS_LOCATION"C396"
$SEC"1"
CDS_SEC"1";
"B"
$PN"2"12;
"A"
$PN"1"6;
%"Q_CAP"
"1","(-1225,8825)","0","pure_quanta","I47";
;
PART_NUMBER"CH647KMEA04"
TOLERANCE"20%"
VOLTAGE"4V"
PACK_TYPE"C0805"
VALUE"47UF"
MATERIAL"X6S"
$LOCATION"C398"
CDS_LIB"pure_quanta"
$LOCATION"C398"
CDS_LOCATION"C398"
$SEC"1"
CDS_SEC"1";
"B"
$PN"2"12;
"A"
$PN"1"6;
%"Q_CAP"
"1","(-775,8825)","0","pure_quanta","I48";
;
PART_NUMBER"CH647KMEA04"
TOLERANCE"20%"
VOLTAGE"4V"
PACK_TYPE"C0805"
VALUE"47UF"
MATERIAL"X6S"
$LOCATION"C366"
CDS_LIB"pure_quanta"
$LOCATION"C366"
CDS_LOCATION"C366"
$SEC"1"
CDS_SEC"1";
"B"
$PN"2"12;
"A"
$PN"1"6;
%"Q_CAP"
"1","(-325,8825)","0","pure_quanta","I49";
;
PART_NUMBER"CH647KMEA04"
TOLERANCE"20%"
VOLTAGE"4V"
PACK_TYPE"C0805"
VALUE"47UF"
MATERIAL"X6S"
$LOCATION"C369"
CDS_LIB"pure_quanta"
$LOCATION"C369"
CDS_LOCATION"C369"
$SEC"1"
CDS_SEC"1";
"B"
$PN"2"12;
"A"
$PN"1"6;
%"Q_CAP"
"1","(-3925,5075)","0","pure_quanta","I5";
;
PART_NUMBER"CH647KMEA04"
MATERIAL"X6S"
TOLERANCE"20%"
VOLTAGE"4V"
PACK_TYPE"C0805"
VALUE"47UF"
$LOCATION"C525"
CDS_LIB"pure_quanta"
CDS_LOCATION"C525"
$SEC"1"
CDS_SEC"1";
"B"
$PN"2"8;
"A"
$PN"1"3;
%"Q_CAP"
"1","(125,8825)","0","pure_quanta","I50";
;
PART_NUMBER"CH647KMEA04"
TOLERANCE"20%"
VOLTAGE"4V"
PACK_TYPE"C0805"
VALUE"47UF"
MATERIAL"X6S"
$LOCATION"C372"
CDS_LIB"pure_quanta"
$LOCATION"C372"
CDS_LOCATION"C372"
$SEC"1"
CDS_SEC"1";
"B"
$PN"2"12;
"A"
$PN"1"6;
%"Q_CAP"
"1","(575,8825)","0","pure_quanta","I51";
;
PART_NUMBER"CH647KMEA04"
TOLERANCE"20%"
VOLTAGE"4V"
PACK_TYPE"C0805"
VALUE"47UF"
MATERIAL"X6S"
$LOCATION"C374"
CDS_LIB"pure_quanta"
$LOCATION"C374"
CDS_LOCATION"C374"
$SEC"1"
CDS_SEC"1";
"B"
$PN"2"12;
"A"
$PN"1"6;
%"Q_CAP"
"1","(1025,8825)","0","pure_quanta","I52";
;
PART_NUMBER"CH647KMEA04"
TOLERANCE"20%"
VOLTAGE"4V"
PACK_TYPE"C0805"
VALUE"47UF"
MATERIAL"X6S"
$LOCATION"C377"
CDS_LIB"pure_quanta"
$LOCATION"C377"
CDS_LOCATION"C377"
$SEC"1"
CDS_SEC"1";
"B"
$PN"2"12;
"A"
$PN"1"6;
%"Q_CAP"
"1","(1475,8825)","0","pure_quanta","I53";
;
PART_NUMBER"CH647KMEA04"
TOLERANCE"20%"
VOLTAGE"4V"
PACK_TYPE"C0805"
VALUE"47UF"
MATERIAL"X6S"
$LOCATION"C380"
CDS_LIB"pure_quanta"
$LOCATION"C380"
CDS_LOCATION"C380"
$SEC"1"
CDS_SEC"1";
"B"
$PN"2"12;
"A"
$PN"1"6;
%"Q_CAP"
"1","(1925,8825)","0","pure_quanta","I54";
;
PART_NUMBER"CH647KMEA04"
TOLERANCE"20%"
VOLTAGE"4V"
PACK_TYPE"C0805"
VALUE"47UF"
MATERIAL"X6S"
$LOCATION"C383"
CDS_LIB"pure_quanta"
$LOCATION"C383"
CDS_LOCATION"C383"
$SEC"1"
CDS_SEC"1";
"B"
$PN"2"12;
"A"
$PN"1"6;
%"UNIVERSAL_GND"
"1","(1925,8475)","0","logical_power","I55";
;
CDS_LIB"logical_power"
HDL_POWER"GND";
"A"12;
%"Q_CAP"
"1","(-3475,5075)","0","pure_quanta","I6";
;
PART_NUMBER"CH647KMEA04"
TOLERANCE"20%"
VOLTAGE"4V"
PACK_TYPE"C0805"
VALUE"47UF"
MATERIAL"X6S"
$LOCATION"C528"
CDS_LIB"pure_quanta"
CDS_LOCATION"C528"
$SEC"1"
CDS_SEC"1";
"B"
$PN"2"8;
"A"
$PN"1"3;
%"Q_CAP"
"1","(-3025,5075)","0","pure_quanta","I7";
;
PART_NUMBER"CH647KMEA04"
PACK_TYPE"C0805"
VOLTAGE"4V"
MATERIAL"X6S"
VALUE"47UF"
TOLERANCE"20%"
$LOCATION"C530"
CDS_LIB"pure_quanta"
CDS_LOCATION"C530"
$SEC"1"
CDS_SEC"1";
"B"
$PN"2"8;
"A"
$PN"1"3;
%"UNIVERSAL_POWER"
"1","(-3925,5350)","0","logical_power","I8";
;
HDL_POWER"PVCCINFAON_CPU0"
CDS_LIB"logical_power";
"A"3;
%"Q_CAP"
"1","(-3925,6100)","0","pure_quanta","I9";
;
PART_NUMBER"CH647KMEA04"
VALUE"47UF"
TOLERANCE"20%"
VOLTAGE"4V"
PACK_TYPE"C0805"
MATERIAL"X6S"
$LOCATION"C500"
CDS_LIB"pure_quanta"
CDS_LOCATION"C500"
$SEC"1"
CDS_SEC"1";
"B"
$PN"2"9;
"A"
$PN"1"1;
END.
